FILE_TYPE = CONNECTIVITY;
{Allegro Design Entry HDL 17.2-2016 S081 (4005846) 1/11/2022}
"PAGE_NUMBER" = 167;
0"NC";
1"PVDD_33_S5_VCC\g";
2"GND\g";
3"GND\g";
4"GND\g";
5"GND\g";
6"GND\g";
7"GND\g";
8"P12V_STBY\g";
9"SW_P12V_STBY_PVDD_33_S5_FLT";
10"GND\g";
11"PVDD33_S5_EN";
12"PVDD_33_S5_VCC\g";
13"PVDD_33_S5_CS";
14"GND\g";
15"PVDD_33_S5_REF";
16"PVDD_33_S5_FB";
17"SW_PVDD_33_S5_BST";
18"SW_PVDD_33_S5_SW";
19"GND\g";
20"PVDD_33_S5\g";
21"PWRGD_PVDD33_S5";
22"FM_PWRGD_PVDD33_S5";
%"Q_CAP"
"1","(-7700,4625)","0","pure_quanta","I15";
;
LOCATION"PC126"
SEC"1"
MATERIAL"X7R"
TOLERANCE"10%"
VALUE"0.1UF"
PART_NUMBER"CH4104K1B00"
VOLTAGE"25V"
PACK_TYPE"0402"
CDS_LIB"pure_quanta"
SEC_TYPE"0402";
"B"
$PN"2"10;
"A"
$PN"1"9;
%"MPQ8633AGLEC807Z"
"1","(-6700,3575)","0","pure_quanta","I18";
;
LOCATION"PU55"
SEC"1"
MATERIAL"IC"
VALUE"MPQ8633AGLE-C807-Z"
PART_NUMBER"AL008633007"
CDS_LIB"pure_quanta"
CDS_LMAN_SYM_OUTLINE"-250,725,250,-725"
PART_TYPE"SMLF"
NEEDS_NO_SIZE"TRUE"
SEC_TYPE"";
"VIN2"
$PN"21"9;
"CS"
$PN"3"13;
"MODE"
$PN"4"12;
"TRK_REF"
$PN"5"15;
"SW"
$PN"20"18;
"RGND"
$PN"6"4;
"VCC"
$PN"19"12;
"AGND"
$PN"2"14;
"FB"
$PN"7"16;
"BST"
$PN"1"17;
"EN"
$PN"8"11;
"PGND"
$PN"11_18"14;
"PGOOD"
$PN"9"21;
"VIN1"
$PN"10"9;
%"Q_CAP"
"1","(-5950,2900)","0","pure_quanta","I19";
;
LOCATION"PC127"
SEC"1"
MATERIAL"X7R"
TOLERANCE"10%"
VALUE"0.1UF"
PART_NUMBER"CH4104K1B00"
VOLTAGE"25V"
PACK_TYPE"0402"
CDS_LIB"pure_quanta"
SEC_TYPE"0402";
"B"
$PN"2"3;
"A"
$PN"1"15;
%"UNIVERSAL_POWER"
"1","(-9800,5000)","0","pure_quanta_power","I2";
;
HDL_POWER"P12V_STBY"
CDS_LIB"pure_quanta_power";
"A"8;
%"Q_RES"
"2","(-6200,4600)","0","pure_quanta","I21";
;
LOCATION"PR453"
SEC"1"
WATTAGE"1/16W"
TOLERANCE"5%"
VALUE"10K"
PART_NUMBER"TMP_QCS31002JB28"
PACK_TYPE"0402LF"
CDS_LIB"pure_quanta"
SEC_TYPE"0402LF"
MATERIAL"CHIP";
"A"
$PN"1"1;
"B"
$PN"2"21;
%"Q_CAP"
"1","(-5600,3900)","0","pure_quanta","I22";
;
LOCATION"PC128"
SEC"1"
MATERIAL"X7R"
VALUE"0.1UF"
PART_NUMBER"CH4104K1B00"
VOLTAGE"25V"
PACK_TYPE"0402"
CDS_LIB"pure_quanta"
SEC_TYPE"0402"
TOLERANCE"10%";
"B"
$PN"2"18;
"A"
$PN"1"17;
%"UNIVERSAL_POWER"
"1","(-6200,4900)","2","pure_quanta_power","I24";
;
HDL_POWER"PVDD_33_S5_VCC"
CDS_LIB"pure_quanta_power";
"A"1;
%"Q_RES"
"2","(-5000,2550)","2","pure_quanta","I26";
;
LOCATION"PR454"
SEC"1"
WATTAGE"1/16W"
MATERIAL"CHIP"
TOLERANCE"1%"
VALUE"12.4K"
PART_NUMBER"CS31242FB13"
PACK_TYPE"0402LF"
CDS_LIB"pure_quanta"
SEC_TYPE"0402LF";
"A"
$PN"1"16;
"B"
$PN"2"5;
%"Q_CAP"
"1","(-4050,2400)","1","pure_quanta","I27";
;
LOCATION"PC132"
SEC"1"
MATERIAL"NPO"
TOLERANCE"5%"
VALUE"100PF"
PART_NUMBER"CH11006JB00"
VOLTAGE"50V"
PACK_TYPE"0402"
CDS_LIB"pure_quanta"
SEC_TYPE"0402";
"B"
$PN"2"20;
"A"
$PN"1"16;
%"Q_RES"
"1","(-4050,2800)","0","pure_quanta","I29";
;
LOCATION"PR455"
SEC"1"
WATTAGE"1/16W"
MATERIAL"CHIP"
TOLERANCE"1%"
VALUE"56K"
PART_NUMBER"TMP_QCS35602FB11"
PACK_TYPE"0402LF"
CDS_LIB"pure_quanta"
SEC_TYPE"0402LF";
"B"
$PN"2"20;
"A"
$PN"1"16;
%"Q_CAP"
"1","(-4400,3450)","0","pure_quanta","I34";
;
LOCATION"PC129"
SEC"1"
MATERIAL"X6S"
TOLERANCE"20%"
VALUE"22UF"
VOLTAGE"16V"
PACK_TYPE"C0805"
SEC_TYPE"C0805"
CDS_LIB"pure_quanta"
PART_NUMBER"CH6223MEA00";
"B"
$PN"2"19;
"A"
$PN"1"20;
%"Q_CAP"
"1","(-4100,3450)","0","pure_quanta","I35";
;
LOCATION"PC130"
SEC"1"
MATERIAL"X6S"
TOLERANCE"20%"
VALUE"22UF"
VOLTAGE"16V"
PACK_TYPE"C0805"
SEC_TYPE"C0805"
CDS_LIB"pure_quanta"
PART_NUMBER"CH6223MEA00";
"B"
$PN"2"19;
"A"
$PN"1"20;
%"Q_CAP"
"1","(-3800,3450)","0","pure_quanta","I36";
;
LOCATION"PC134"
SEC"1"
MATERIAL"X6S"
TOLERANCE"20%"
VALUE"22UF"
VOLTAGE"16V"
PACK_TYPE"C0805"
SEC_TYPE"C0805"
CDS_LIB"pure_quanta"
PART_NUMBER"CH6223MEA00";
"B"
$PN"2"19;
"A"
$PN"1"20;
%"Q_CAP"
"1","(-3500,3450)","0","pure_quanta","I37";
;
LOCATION"PC135"
SEC"1"
MATERIAL"X6S"
TOLERANCE"20%"
VALUE"22UF"
PART_NUMBER"CH6223MEA00"
VOLTAGE"16V"
PACK_TYPE"C0805"
SEC_TYPE"C0805"
CDS_LIB"pure_quanta";
"B"
$PN"2"19;
"A"
$PN"1"20;
%"Q_CAP"
"1","(-3100,3450)","0","pure_quanta","I39";
;
LOCATION"PC136"
SEC"1"
MATERIAL"X7R"
TOLERANCE"10%"
VALUE"0.1UF"
PART_NUMBER"CH4104K1B00"
VOLTAGE"25V"
PACK_TYPE"0402"
SEC_TYPE"0402"
CDS_LIB"pure_quanta";
"B"
$PN"2"19;
"A"
$PN"1"20;
%"UNIVERSAL_POWER"
"1","(-2650,3900)","0","pure_quanta_power","I40";
;
HDL_POWER"PVDD_33_S5"
CDS_LIB"pure_quanta_power";
"A"20;
%"UNIVERSAL_GND"
"1","(-9000,4250)","0","pure_quanta_power","I41";
;
CDS_LIB"pure_quanta_power"
HDL_POWER"GND";
"A"10;
%"UNIVERSAL_GND"
"1","(-7700,2450)","0","pure_quanta_power","I44";
;
CDS_LIB"pure_quanta_power"
HDL_POWER"GND";
"A"2;
%"UNIVERSAL_GND"
"1","(-6200,2700)","0","pure_quanta_power","I45";
;
CDS_LIB"pure_quanta_power"
HDL_POWER"GND";
"A"14;
%"UNIVERSAL_GND"
"1","(-5950,2700)","0","pure_quanta_power","I46";
;
CDS_LIB"pure_quanta_power"
HDL_POWER"GND";
"A"3;
%"UNIVERSAL_GND"
"1","(-5600,2700)","0","pure_quanta_power","I47";
;
CDS_LIB"pure_quanta_power"
HDL_POWER"GND";
"A"4;
%"UNIVERSAL_GND"
"1","(-5000,2275)","0","pure_quanta_power","I48";
;
CDS_LIB"pure_quanta_power"
HDL_POWER"GND";
"A"5;
%"UNIVERSAL_GND"
"1","(-3100,3050)","0","pure_quanta_power","I49";
;
CDS_LIB"pure_quanta_power"
HDL_POWER"GND";
"A"19;
%"Q_RES"
"2","(-7700,2725)","0","pure_quanta","I5";
;
LOCATION"PR452"
SEC"1"
WATTAGE"1/16W"
MATERIAL"CHIP"
TOLERANCE"1%"
VALUE"6.98K"
PART_NUMBER"CS26982FB08"
PACK_TYPE"0402LF"
SEC_TYPE"0402LF"
CDS_LIB"pure_quanta";
"A"
$PN"1"13;
"B"
$PN"2"2;
%"Q_INDUCTOR"
"1","(-9400,4825)","0","pure_quanta","I50";
;
LOCATION"PL71"
SEC"1"
MATERIAL"IND"
VALUE"BLM18SN220TN1D/8000MA"
PART_NUMBER"CX220TN1001"
PACK_TYPE"SMLF"
CDS_LIB"pure_quanta"
NEEDS_NO_SIZE"TRUE"
SEC_TYPE"SMLF";
"1"
$PN"1"8;
"2"
$PN"2"9;
%"UNIVERSAL_GND"
"1","(-8275,2375)","0","pure_quanta_power","I51";
;
CDS_LIB"pure_quanta_power"
HDL_POWER"GND";
"A"6;
%"Q_CAP"
"1","(-8275,2650)","2","pure_quanta","I52";
;
LOCATION"PC118"
SEC"1"
MATERIAL"X6S"
TOLERANCE"10%"
VALUE"1UF"
PART_NUMBER"CH5104KEB02"
VOLTAGE"25V"
PACK_TYPE"C0402"
SIGNAL_MODEL"DEFAULT_CAPACITOR_100000PF_2_1"
CDS_LIB"pure_quanta"
SEC_TYPE"C0402"
ROOM"VR_DDR0_CTRL";
"B"
$PN"2"6;
"A"
$PN"1"12;
%"UNIVERSAL_POWER"
"1","(-8275,3200)","0","pure_quanta_power","I53";
;
HDL_POWER"PVDD_33_S5_VCC"
CDS_LIB"pure_quanta_power";
"A"12;
%"Q_INDUCTOR"
"1","(-5000,3775)","0","pure_quanta","I56";
;
LOCATION"PL72"
$SEC"1"
CDS_SEC"1"
MATERIAL"IND"
VALUE"2.2UH"
PART_NUMBER"CV-2280MZ15"
PACK_TYPE"SMLF"
CDS_LIB"pure_quanta"
NEEDS_NO_SIZE"TRUE";
"1"
$PN"1"18;
"2"
$PN"2"20;
%"UNIVERSAL_GND"
"1","(-8300,3375)","0","pure_quanta_power","I57";
;
CDS_LIB"pure_quanta_power"
HDL_POWER"GND";
"A"7;
%"Q_CAP"
"1","(-8300,3575)","2","pure_quanta","I58";
;
LOCATION"C348"
$SEC"1"
CDS_SEC"1"
MATERIAL"EMPTY"
TOLERANCE"10%"
VALUE"0.1UF"
PART_NUMBER"CH4104K1B00"
VOLTAGE"25V"
PACK_TYPE"0402"
CDS_LIB"pure_quanta"
ROOM"VR_DDR0_CTRL";
"B"
$PN"2"7;
"A"
$PN"1"11;
%"Q_RES"
"1","(-5050,4250)","0","pure_quanta","I60";
;
LOCATION"R225"
$SEC"1"
CDS_SEC"1"
VALUE"33"
CDS_LIB"pure_quanta"
BOM_COST"MEM"
WATTAGE"1/16W"
MATERIAL"CHIP"
TOLERANCE"5%"
PART_NUMBER"CS03302JB29"
PACK_TYPE"0402LF"
ROOM"RST_CPU0_PLD_TO_DIMM";
"B"
$PN"2"22;
"A"
$PN"1"21;
%"Q_CAP"
"1","(-9000,4625)","0","pure_quanta","I7";
;
LOCATION"PC119"
SEC"1"
MATERIAL"X6S"
TOLERANCE"10%"
VALUE"10UF"
PART_NUMBER"CH6104KEA00"
VOLTAGE"25V"
PACK_TYPE"C0805"
SEC_TYPE"C0805"
CDS_LIB"pure_quanta";
"B"
$PN"2"10;
"A"
$PN"1"9;
%"Q_CAP"
"1","(-8500,4625)","0","pure_quanta","I8";
;
LOCATION"PC120"
SEC"1"
MATERIAL"X6S"
TOLERANCE"10%"
VALUE"10UF"
VOLTAGE"25V"
PACK_TYPE"C0805"
SEC_TYPE"C0805"
CDS_LIB"pure_quanta"
PART_NUMBER"CH6104KEA00";
"B"
$PN"2"10;
"A"
$PN"1"9;
%"Q_CAP"
"1","(-8100,4625)","0","pure_quanta","I9";
;
LOCATION"PC123"
SEC"1"
MATERIAL"X6S"
TOLERANCE"10%"
VALUE"10UF"
VOLTAGE"25V"
PACK_TYPE"C0805"
SEC_TYPE"C0805"
CDS_LIB"pure_quanta"
PART_NUMBER"CH6104KEA00";
"B"
$PN"2"10;
"A"
$PN"1"9;
END.
